#ISCELL
  pure_quanta quanta_title_block_c *
  *
#ISCELL
  logical_power universal_gnd *
  page310_i1
#CELL
  pure_quanta tp_tdr_4p_fts *
  page310_i10
#ISCELL
  logical_power universal_gnd *
  page310_i11
#ISCELL
  logical_power universal_gnd *
  page310_i12
#ISCELL
  logical_power universal_gnd *
  page310_i13
#ISCELL
  logical_power universal_gnd *
  page310_i14
#CELL
  pure_quanta tp_tdr_4p_fts *
  page310_i15
#CELL
  pure_quanta tp_tdr_4p_fts *
  page310_i16
#ISCELL
  logical_power universal_gnd *
  page310_i17
#ISCELL
  logical_power universal_gnd *
  page310_i18
#CELL
  pure_quanta tp_tdr_4p_fts *
  page310_i19
#ISCELL
  logical_power universal_gnd *
  page310_i2
#CELL
  pure_quanta tp_tdr_4p_fts *
  page310_i20
#CELL
  pure_quanta tp_tdr_4p_fts *
  page310_i21
#CELL
  pure_quanta tp_tdr_4p_fts *
  page310_i22
#ISCELL
  logical_power universal_gnd *
  page310_i23
#ISCELL
  logical_power universal_gnd *
  page310_i24
#ISCELL
  logical_power universal_gnd *
  page310_i3
#ISCELL
  logical_power universal_gnd *
  page310_i4
#CELL
  pure_quanta tp_tdr_4p_fts *
  page310_i5
#CELL
  pure_quanta tp_tdr_4p_fts *
  page310_i6
#CELL
  pure_quanta tp_tdr_4p_fts *
  page310_i7
#CELL
  pure_quanta tp_tdr_4p_fts *
  page310_i8
#CELL
  pure_quanta tp_tdr_4p_fts *
  page310_i9
